(kicad_pcb
	(version 20241229)
	(generator "pcbnew")
	(generator_version "9.0")
	(general
		(thickness 1.711)
		(legacy_teardrops no)
	)
	(paper "A4")
	(title_block
		(title "Antmicro Baseboard for Jetson AGX Thor")
		(date "2026-02-18")
		(rev "1.1.0")
		(company "Antmicro Ltd")
		(comment 1 "www.antmicro.com")
		(comment 9 "footprints 1127-1131 of 1170")
	)
	(layers
		(0 "F.Cu" signal)
		(4 "In1.Cu" signal)
		(6 "In2.Cu" signal)
		(8 "In3.Cu" signal)
		(10 "In4.Cu" jumper)
		(12 "In5.Cu" signal)
		(14 "In6.Cu" signal)
		(16 "In7.Cu" signal)
		(18 "In8.Cu" signal)
		(2 "B.Cu" signal)
		(9 "F.Adhes" user "F.Adhesive")
		(11 "B.Adhes" user "B.Adhesive")
		(13 "F.Paste" user)
		(15 "B.Paste" user)
		(5 "F.SilkS" user "F.Silkscreen")
		(7 "B.SilkS" user "B.Silkscreen")
		(1 "F.Mask" user)
		(3 "B.Mask" user)
		(17 "Dwgs.User" user "User.Drawings")
		(19 "Cmts.User" user "User.Comments")
		(21 "Eco1.User" user "User.Eco1")
		(23 "Eco2.User" user "User.Eco2")
		(25 "Edge.Cuts" user)
		(27 "Margin" user)
		(31 "F.CrtYd" user "F.Courtyard")
		(29 "B.CrtYd" user "B.Courtyard")
		(35 "F.Fab" user)
		(33 "B.Fab" user)
	)
	(footprint "antmicro-footprints:C_0402_1005Metric"
		(layer "B.Cu")
		(at 92.180001 103.6 -90)
		(descr "Capacitor SMD 0402")
		(tags "capacitor SMD 0402")
		(property "Reference" "C327"
			(at -3.8 -0.419999 90)
			(layer "B.SilkS")
			(effects
				(font
					(size 0.7 0.7)
					(thickness 0.15)
				)
				(justify left bottom mirror)
			)
		)
		(property "Value" "C_100n_0402"
			(at -1.022927 -2.155213 90)
			(layer "B.Fab")
			(effects
				(font
					(size 0.7 0.7)
					(thickness 0.15)
				)
				(justify left bottom mirror)
			)
		)
		(property "Datasheet" "https://www.murata.com/products/productdetail?partno=GRM155R61H104KE14%23"
			(at 0 0 90)
			(layer "B.Fab")
			(hide yes)
			(effects
				(font
					(size 1.27 1.27)
					(thickness 0.15)
				)
				(justify mirror)
			)
		)
		(property "Description" "SMD Multilayer Ceramic Capacitor, 0.1 µF, 50 V, 0402 [1005 Metric], ± 10%, X5R, GRM Series"
			(at 0 0 90)
			(layer "B.Fab")
			(hide yes)
			(effects
				(font
					(size 1.27 1.27)
					(thickness 0.15)
				)
				(justify mirror)
			)
		)
		(property "Manufacturer" "Murata"
			(at 0 0 90)
			(unlocked yes)
			(layer "B.Fab")
			(hide yes)
			(effects
				(font
					(size 1 1)
					(thickness 0.15)
				)
				(justify mirror)
			)
		)
		(property "MPN" "GRM155R61H104KE14D"
			(at 0 0 90)
			(unlocked yes)
			(layer "B.Fab")
			(hide yes)
			(effects
				(font
					(size 1 1)
					(thickness 0.15)
				)
				(justify mirror)
			)
		)
		(property "Val" "100n"
			(at 0 0 90)
			(unlocked yes)
			(layer "B.Fab")
			(hide yes)
			(effects
				(font
					(size 1 1)
					(thickness 0.15)
				)
				(justify mirror)
			)
		)
		(property "License" "Apache-2.0"
			(at 0 0 90)
			(unlocked yes)
			(layer "B.Fab")
			(hide yes)
			(effects
				(font
					(size 1 1)
					(thickness 0.15)
				)
				(justify mirror)
			)
		)
		(property "Author" "Antmicro"
			(at 0 0 90)
			(unlocked yes)
			(layer "B.Fab")
			(hide yes)
			(effects
				(font
					(size 1 1)
					(thickness 0.15)
				)
				(justify mirror)
			)
		)
		(property "Voltage" "50V"
			(at 0 0 90)
			(unlocked yes)
			(layer "B.Fab")
			(hide yes)
			(effects
				(font
					(size 1 1)
					(thickness 0.15)
				)
				(justify mirror)
			)
		)
		(property "Dielectric" "X5R"
			(at 0 0 90)
			(unlocked yes)
			(layer "B.Fab")
			(hide yes)
			(effects
				(font
					(size 1 1)
					(thickness 0.15)
				)
				(justify mirror)
			)
		)
		(sheetname "/SoM_IO2/")
		(sheetfile "som_io2.kicad_sch")
		(attr smd)
		(fp_poly
			(pts
				(xy -0.925 0.47) (xy 0.925 0.47) (xy 0.925 -0.47) (xy -0.925 -0.47)
			)
			(stroke
				(width 0.05)
				(type default)
			)
			(fill no)
			(layer "B.CrtYd")
		)
		(fp_line
			(start -0.494 0.25)
			(end 0.504 0.25)
			(stroke
				(width 0.15)
				(type solid)
			)
			(layer "B.Fab")
		)
		(fp_line
			(start 0.504 0.25)
			(end 0.504 -0.248)
			(stroke
				(width 0.15)
				(type solid)
			)
			(layer "B.Fab")
		)
		(fp_line
			(start -0.494 -0.248)
			(end -0.494 0.25)
			(stroke
				(width 0.15)
				(type solid)
			)
			(layer "B.Fab")
		)
		(fp_line
			(start 0.504 -0.248)
			(end -0.494 -0.248)
			(stroke
				(width 0.15)
				(type solid)
			)
			(layer "B.Fab")
		)
		(fp_text user "License: Apache-2.0"
			(at -0.939 -5.799 90)
			(layer "B.Fab")
			(effects
				(font
					(size 0.7 0.7)
					(thickness 0.15)
				)
				(justify left bottom mirror)
			)
		)
		(fp_text user "Author: Antmicro"
			(at -0.939 -3.399 90)
			(layer "B.Fab")
			(effects
				(font
					(size 0.7 0.7)
					(thickness 0.15)
				)
				(justify left bottom mirror)
			)
		)
		(fp_text user "${REFERENCE}"
			(at -0.939 -4.599 90)
			(layer "B.Fab")
			(effects
				(font
					(size 0.7 0.7)
					(thickness 0.15)
				)
				(justify left bottom mirror)
			)
		)
		(pad "1" smd roundrect
			(at -0.48 0 270)
			(size 0.59 0.64)
			(layers "B.Cu" "B.Mask" "B.Paste")
			(roundrect_rratio 0.25)
			(net 794 "/Expansion connector/DP1.TX3+")
			(pintype "passive")
		)
		(pad "2" smd roundrect
			(at 0.48 0 270)
			(size 0.59 0.64)
			(layers "B.Cu" "B.Mask" "B.Paste")
			(roundrect_rratio 0.25)
			(net 1247 "/SoM_IO2/DP1.TX3_C+")
			(pintype "passive")
		)
	)
	(footprint "antmicro-footprints:Conn_JST_SH_1x4_SM04B-SRSS-TB-LF-SN"
		(locked yes)
		(layer "B.Cu")
		(at 147.13 56.86)
		(property "Reference" "J17"
			(at 3.97 -0.96 270)
			(layer "B.SilkS")
			(effects
				(font
					(size 0.7 0.7)
					(thickness 0.15)
				)
				(justify right top mirror)
			)
		)
		(property "Value" "JST_SH_1x4_SM04B-SRSS-TB-LF-SN"
			(at -4 -3.88 0)
			(layer "B.Fab")
			(effects
				(font
					(size 0.7 0.7)
					(thickness 0.15)
				)
				(justify right top mirror)
			)
		)
		(property "Datasheet" "https://www.jst-mfg.com/product/pdf/eng/eSH.pdf"
			(at 0 0 0)
			(layer "B.Fab")
			(hide yes)
			(effects
				(font
					(size 1.27 1.27)
					(thickness 0.15)
				)
				(justify mirror)
			)
		)
		(property "Description" "Pin Header, Right Angle, Wire-to-Board, 1 mm, 1 Rows, 4 Contacts, Surface Mount Right Angle, SH"
			(at 0 0 0)
			(layer "B.Fab")
			(hide yes)
			(effects
				(font
					(size 1.27 1.27)
					(thickness 0.15)
				)
				(justify mirror)
			)
		)
		(property "MPN" "SM04B-SRSS-TB(LF)(SN)"
			(at 0 0 180)
			(unlocked yes)
			(layer "B.Fab")
			(hide yes)
			(effects
				(font
					(size 1 1)
					(thickness 0.15)
				)
				(justify mirror)
			)
		)
		(property "Manufacturer" "JST Automotive Connectors"
			(at 0 0 180)
			(unlocked yes)
			(layer "B.Fab")
			(hide yes)
			(effects
				(font
					(size 1 1)
					(thickness 0.15)
				)
				(justify mirror)
			)
		)
		(property "Author" "Antmicro"
			(at 0 0 180)
			(unlocked yes)
			(layer "B.Fab")
			(hide yes)
			(effects
				(font
					(size 1 1)
					(thickness 0.15)
				)
				(justify mirror)
			)
		)
		(property "License" "Apache-2.0"
			(at 0 0 180)
			(unlocked yes)
			(layer "B.Fab")
			(hide yes)
			(effects
				(font
					(size 1 1)
					(thickness 0.15)
				)
				(justify mirror)
			)
		)
		(sheetname "/Peripherals/")
		(sheetfile "peripherals.kicad_sch")
		(attr smd)
		(fp_line
			(start -3.2 2)
			(end -3.2 -0.6)
			(stroke
				(width 0.15)
				(type solid)
			)
			(layer "B.SilkS")
		)
		(fp_line
			(start -2 -2.6)
			(end 2 -2.6)
			(stroke
				(width 0.15)
				(type solid)
			)
			(layer "B.SilkS")
		)
		(fp_line
			(start -2 2)
			(end -3.2 2)
			(stroke
				(width 0.15)
				(type solid)
			)
			(layer "B.SilkS")
		)
		(fp_line
			(start 2 2)
			(end 3.2 2)
			(stroke
				(width 0.15)
				(type solid)
			)
			(layer "B.SilkS")
		)
		(fp_line
			(start 3.2 2)
			(end 3.2 -0.6)
			(stroke
				(width 0.15)
				(type solid)
			)
			(layer "B.SilkS")
		)
		(fp_circle
			(center -2.1 2.5)
			(end -2.05 2.5)
			(stroke
				(width 0.15)
				(type solid)
			)
			(fill yes)
			(layer "B.SilkS")
		)
		(fp_rect
			(start -3.65 3.14)
			(end 3.65 -2.9)
			(stroke
				(width 0.05)
				(type solid)
			)
			(fill no)
			(layer "B.CrtYd")
		)
		(fp_rect
			(start -3 2.475)
			(end 3 -2.475)
			(stroke
				(width 0.15)
				(type solid)
			)
			(fill no)
			(layer "B.Fab")
		)
		(fp_text user "${REFERENCE}"
			(at -4 -8.28 0)
			(layer "B.Fab")
			(effects
				(font
					(size 0.7 0.7)
					(thickness 0.15)
				)
				(justify right top mirror)
			)
		)
		(fp_text user "Author: Antmicro"
			(at -4 -7.08 0)
			(layer "B.Fab")
			(effects
				(font
					(size 0.7 0.7)
					(thickness 0.15)
				)
				(justify right top mirror)
			)
		)
		(fp_text user "License: Apache-2.0"
			(at -4 -5.88 0)
			(layer "B.Fab")
			(effects
				(font
					(size 0.7 0.7)
					(thickness 0.15)
				)
				(justify right top mirror)
			)
		)
		(pad "1" smd roundrect
			(at -1.5 2.12 180)
			(size 0.6 1.55)
			(layers "B.Cu" "B.Mask" "B.Paste")
			(roundrect_rratio 0.25)
			(net 1 "GND")
			(pintype "passive")
		)
		(pad "2" smd roundrect
			(at -0.5 2.12 180)
			(size 0.6 1.55)
			(layers "B.Cu" "B.Mask" "B.Paste")
			(roundrect_rratio 0.25)
			(net 839 "/Peripherals/I2C_CONN2_3V3")
			(pintype "passive")
		)
		(pad "3" smd roundrect
			(at 0.5 2.12 180)
			(size 0.6 1.55)
			(layers "B.Cu" "B.Mask" "B.Paste")
			(roundrect_rratio 0.25)
			(net 43 "/Peripherals/I2C_{CONN}.SDA")
			(pintype "passive")
		)
		(pad "4" smd roundrect
			(at 1.5 2.12 180)
			(size 0.6 1.55)
			(layers "B.Cu" "B.Mask" "B.Paste")
			(roundrect_rratio 0.25)
			(net 42 "/Peripherals/I2C_{CONN}.SCL")
			(pintype "passive")
		)
		(pad "MP" smd roundrect
			(at -2.8 -1.755)
			(size 1.2 1.8)
			(layers "B.Cu" "B.Mask" "B.Paste")
			(roundrect_rratio 0.25)
			(net 1 "GND")
			(pintype "passive")
		)
		(pad "MP" smd roundrect
			(at 2.8 -1.755)
			(size 1.2 1.8)
			(layers "B.Cu" "B.Mask" "B.Paste")
			(roundrect_rratio 0.25)
			(net 1 "GND")
			(pintype "passive")
		)
	)
	(footprint "antmicro-footprints:R_0402_1005Metric"
		(layer "B.Cu")
		(at 164 57.5 -90)
		(descr "Resistor SMD 0402")
		(tags "resistor SMD 0402")
		(property "Reference" "R257"
			(at -3.62 -0.335532 90)
			(layer "B.SilkS")
			(effects
				(font
					(size 0.7 0.7)
					(thickness 0.15)
				)
				(justify left bottom mirror)
			)
		)
		(property "Value" "R_470R_0402"
			(at -1.011843 -1.772047 90)
			(layer "B.Fab")
			(effects
				(font
					(size 0.7 0.7)
					(thickness 0.15)
				)
				(justify left bottom mirror)
			)
		)
		(property "Datasheet" "https://www.bourns.com/docs/product-datasheets/cr.pdf"
			(at 0 0 90)
			(layer "B.Fab")
			(hide yes)
			(effects
				(font
					(size 1.27 1.27)
					(thickness 0.15)
				)
				(justify mirror)
			)
		)
		(property "Description" "SMD Chip Resistor, 470 ohm, ± 1%, 62.5 mW, 0402 [1005 Metric], Thick Film, General Purpose"
			(at 0 0 90)
			(layer "B.Fab")
			(hide yes)
			(effects
				(font
					(size 1.27 1.27)
					(thickness 0.15)
				)
				(justify mirror)
			)
		)
		(property "Manufacturer" "Bourns"
			(at 0 0 90)
			(unlocked yes)
			(layer "B.Fab")
			(hide yes)
			(effects
				(font
					(size 1 1)
					(thickness 0.15)
				)
				(justify mirror)
			)
		)
		(property "MPN" "CR0402-FX-4700GLF"
			(at 0 0 90)
			(unlocked yes)
			(layer "B.Fab")
			(hide yes)
			(effects
				(font
					(size 1 1)
					(thickness 0.15)
				)
				(justify mirror)
			)
		)
		(property "Val" "470R"
			(at 0 0 90)
			(unlocked yes)
			(layer "B.Fab")
			(hide yes)
			(effects
				(font
					(size 1 1)
					(thickness 0.15)
				)
				(justify mirror)
			)
		)
		(property "License" "Apache-2.0"
			(at 0 0 90)
			(unlocked yes)
			(layer "B.Fab")
			(hide yes)
			(effects
				(font
					(size 1 1)
					(thickness 0.15)
				)
				(justify mirror)
			)
		)
		(property "Author" "Antmicro"
			(at 0 0 90)
			(unlocked yes)
			(layer "B.Fab")
			(hide yes)
			(effects
				(font
					(size 1 1)
					(thickness 0.15)
				)
				(justify mirror)
			)
		)
		(property "Tolerance" "1%"
			(at 0 0 90)
			(unlocked yes)
			(layer "B.Fab")
			(hide yes)
			(effects
				(font
					(size 1 1)
					(thickness 0.15)
				)
				(justify mirror)
			)
		)
		(sheetname "/Power/")
		(sheetfile "power.kicad_sch")
		(attr smd)
		(fp_rect
			(start -0.925 0.47)
			(end 0.925 -0.47)
			(stroke
				(width 0.05)
				(type default)
			)
			(fill no)
			(layer "B.CrtYd")
		)
		(fp_rect
			(start -0.5 0.25)
			(end 0.5 -0.25)
			(stroke
				(width 0.15)
				(type solid)
			)
			(fill no)
			(layer "B.Fab")
		)
		(fp_text user "Author: Antmicro"
			(at -0.95 -4.169 90)
			(layer "B.Fab")
			(effects
				(font
					(size 0.7 0.7)
					(thickness 0.15)
				)
				(justify left bottom mirror)
			)
		)
		(fp_text user "License: Apache-2.0"
			(at -0.95 -5.169 90)
			(layer "B.Fab")
			(effects
				(font
					(size 0.7 0.7)
					(thickness 0.15)
				)
				(justify left bottom mirror)
			)
		)
		(fp_text user "${REFERENCE}"
			(at -0.95 -3.168 90)
			(layer "B.Fab")
			(effects
				(font
					(size 0.7 0.7)
					(thickness 0.15)
				)
				(justify left bottom mirror)
			)
		)
		(pad "1" smd roundrect
			(at -0.48 0 270)
			(size 0.59 0.64)
			(layers "B.Cu" "B.Mask" "B.Paste")
			(roundrect_rratio 0.25)
			(net 645 "Net-(D43-A)")
			(pintype "passive")
		)
		(pad "2" smd roundrect
			(at 0.48 0 270)
			(size 0.59 0.64)
			(layers "B.Cu" "B.Mask" "B.Paste")
			(roundrect_rratio 0.25)
			(net 5 "+5V")
			(pintype "passive")
		)
	)
	(footprint "antmicro-footprints:R_0402_1005Metric"
		(layer "B.Cu")
		(at 196.6 131.65 90)
		(descr "Resistor SMD 0402")
		(tags "resistor SMD 0402")
		(property "Reference" "R322"
			(at -1.32 0.578198 90)
			(layer "B.SilkS")
			(effects
				(font
					(size 0.7 0.7)
					(thickness 0.15)
				)
				(justify right top mirror)
			)
		)
		(property "Value" "R_200k_0402"
			(at -1.011843 -1.772046 90)
			(layer "B.Fab")
			(effects
				(font
					(size 0.7 0.7)
					(thickness 0.15)
				)
				(justify right top mirror)
			)
		)
		(property "Datasheet" "https://www.bourns.com/docs/product-datasheets/cr.pdf"
			(at 0 0 90)
			(layer "B.Fab")
			(hide yes)
			(effects
				(font
					(size 1.27 1.27)
					(thickness 0.15)
				)
				(justify mirror)
			)
		)
		(property "Description" "SMD Chip Resistor, 200 kohm, ± 1%, 62.5 mW, 0402 [1005 Metric], Thick Film, General Purpose"
			(at 0 0 90)
			(layer "B.Fab")
			(hide yes)
			(effects
				(font
					(size 1.27 1.27)
					(thickness 0.15)
				)
				(justify mirror)
			)
		)
		(property "MPN" "CR0402-FX-2003GLF"
			(at 0 0 270)
			(unlocked yes)
			(layer "B.Fab")
			(hide yes)
			(effects
				(font
					(size 1 1)
					(thickness 0.15)
				)
				(justify mirror)
			)
		)
		(property "Manufacturer" "Bourns"
			(at 0 0 270)
			(unlocked yes)
			(layer "B.Fab")
			(hide yes)
			(effects
				(font
					(size 1 1)
					(thickness 0.15)
				)
				(justify mirror)
			)
		)
		(property "License" "Apache-2.0"
			(at 0 0 270)
			(unlocked yes)
			(layer "B.Fab")
			(hide yes)
			(effects
				(font
					(size 1 1)
					(thickness 0.15)
				)
				(justify mirror)
			)
		)
		(property "Author" "Antmicro"
			(at 0 0 270)
			(unlocked yes)
			(layer "B.Fab")
			(hide yes)
			(effects
				(font
					(size 1 1)
					(thickness 0.15)
				)
				(justify mirror)
			)
		)
		(property "Val" "200k"
			(at 0 0 270)
			(unlocked yes)
			(layer "B.Fab")
			(hide yes)
			(effects
				(font
					(size 1 1)
					(thickness 0.15)
				)
				(justify mirror)
			)
		)
		(property "Tolerance" "1%"
			(at 0 0 270)
			(unlocked yes)
			(layer "B.Fab")
			(hide yes)
			(effects
				(font
					(size 1 1)
					(thickness 0.15)
				)
				(justify mirror)
			)
		)
		(sheetname "/USB Hub/")
		(sheetfile "usb_hub.kicad_sch")
		(attr smd)
		(fp_poly
			(pts
				(xy -0.925 0.47) (xy -0.925 -0.47) (xy 0.925 -0.47) (xy 0.925 0.47)
			)
			(stroke
				(width 0.05)
				(type default)
			)
			(fill no)
			(layer "B.CrtYd")
		)
		(fp_poly
			(pts
				(xy -0.5 0.25) (xy -0.5 -0.25) (xy 0.5 -0.25) (xy 0.5 0.25)
			)
			(stroke
				(width 0.15)
				(type solid)
			)
			(fill no)
			(layer "B.Fab")
		)
		(fp_text user "Author: Antmicro"
			(at -0.95 -4.169 90)
			(layer "B.Fab")
			(effects
				(font
					(size 0.7 0.7)
					(thickness 0.15)
				)
				(justify right top mirror)
			)
		)
		(fp_text user "License: Apache-2.0"
			(at -0.949999 -5.169 90)
			(layer "B.Fab")
			(effects
				(font
					(size 0.7 0.7)
					(thickness 0.15)
				)
				(justify right top mirror)
			)
		)
		(fp_text user "${REFERENCE}"
			(at -0.95 -3.168 90)
			(layer "B.Fab")
			(effects
				(font
					(size 0.7 0.7)
					(thickness 0.15)
				)
				(justify right top mirror)
			)
		)
		(pad "1" smd roundrect
			(at -0.48 0 90)
			(size 0.59 0.64)
			(layers "B.Cu" "B.Mask" "B.Paste")
			(roundrect_rratio 0.25)
			(net 1 "GND")
			(pintype "passive")
		)
		(pad "2" smd roundrect
			(at 0.48 0 90)
			(size 0.59 0.64)
			(layers "B.Cu" "B.Mask" "B.Paste")
			(roundrect_rratio 0.25)
			(net 930 "/USB Hub/HUB_SPI_CE_N")
			(pintype "passive")
		)
	)
	(footprint "antmicro-footprints:TP_SMD_0.75mm"
		(layer "B.Cu")
		(at 217.4 90.81 -90)
		(property "Reference" "TP17"
			(at 0.39 -3.3 0)
			(layer "B.SilkS")
			(effects
				(font
					(size 0.7 0.7)
					(thickness 0.15)
				)
				(justify left bottom mirror)
			)
		)
		(property "Value" "TP_0.75mm_SMD"
			(at 0 -1.2 90)
			(layer "B.Fab")
			(effects
				(font
					(size 0.7 0.7)
					(thickness 0.15)
				)
				(justify left bottom mirror)
			)
		)
		(property "Description" "SMT test point"
			(at 0 0 90)
			(layer "B.Fab")
			(hide yes)
			(effects
				(font
					(size 1.27 1.27)
					(thickness 0.15)
				)
				(justify mirror)
			)
		)
		(property "MPN" ""
			(at 0 0 90)
			(unlocked yes)
			(layer "B.Fab")
			(hide yes)
			(effects
				(font
					(size 1 1)
					(thickness 0.15)
				)
				(justify mirror)
			)
		)
		(property "Manufacturer" ""
			(at 0 0 90)
			(unlocked yes)
			(layer "B.Fab")
			(hide yes)
			(effects
				(font
					(size 1 1)
					(thickness 0.15)
				)
				(justify mirror)
			)
		)
		(property "Author" "Antmicro"
			(at 0 0 90)
			(unlocked yes)
			(layer "B.Fab")
			(hide yes)
			(effects
				(font
					(size 1 1)
					(thickness 0.15)
				)
				(justify mirror)
			)
		)
		(property "License" "Apache-2.0"
			(at 0 0 90)
			(unlocked yes)
			(layer "B.Fab")
			(hide yes)
			(effects
				(font
					(size 1 1)
					(thickness 0.15)
				)
				(justify mirror)
			)
		)
		(sheetname "/USB DP Alt mode/")
		(sheetfile "usb_dp.kicad_sch")
		(attr exclude_from_pos_files exclude_from_bom)
		(fp_circle
			(center 0 0)
			(end 0.475 0)
			(stroke
				(width 0.05)
				(type default)
			)
			(fill no)
			(layer "B.CrtYd")
		)
		(fp_text user "Author: Antmicro"
			(at -0.4 -3.901 90)
			(layer "B.Fab")
			(effects
				(font
					(size 0.7 0.7)
					(thickness 0.15)
				)
				(justify left bottom mirror)
			)
		)
		(fp_text user "${REFERENCE}"
			(at -0.4 -2.7 90)
			(layer "B.Fab")
			(effects
				(font
					(size 0.7 0.7)
					(thickness 0.15)
				)
				(justify left bottom mirror)
			)
		)
		(fp_text user "License: Apache-2.0"
			(at -0.4 -5.101 90)
			(layer "B.Fab")
			(effects
				(font
					(size 0.7 0.7)
					(thickness 0.15)
				)
				(justify left bottom mirror)
			)
		)
		(pad "1" smd circle
			(at -0.01 0 270)
			(size 0.75 0.75)
			(layers "B.Cu" "B.Mask")
			(net 957 "/USB DP Alt mode/HPDIN")
			(pinfunction "1")
			(pintype "passive")
		)
	)
)
